(kicad_pcb
	(version 20260206)
	(generator "pcbnew")
	(generator_version "10.0")
	(general
		(thickness 1.6)
		(legacy_teardrops no)
	)
	(paper "A4")
	(title_block
		(title "Bryce Canyon_F.DPB_16315-1-OCP.brd")
		(comment 1 "Bryce Canyon / footprints 48-51 of 2223")
	)
	(layers
		(0 "F.Cu" signal "TOP")
		(4 "In1.Cu" signal "L2GND")
		(6 "In2.Cu" signal "L3")
		(8 "In3.Cu" signal "L4GND")
		(10 "In4.Cu" signal "L5")
		(12 "In5.Cu" signal "L6VCC")
		(14 "In6.Cu" signal "L7VCC")
		(16 "In7.Cu" signal "L8")
		(18 "In8.Cu" signal "L9GND")
		(20 "In9.Cu" signal "L10")
		(22 "In10.Cu" signal "L11GND")
		(2 "B.Cu" signal "BOTTOM")
		(9 "F.Adhes" user "F.Adhesive")
		(11 "B.Adhes" user "B.Adhesive")
		(13 "F.Paste" user "Package Geometry/Pastemask Top")
		(15 "B.Paste" user "Package Geometry/Pastemask Bottom")
		(5 "F.SilkS" user "Ref Des/Silkscreen Top")
		(7 "B.SilkS" user "Ref Des/Silkscreen Bottom")
		(1 "F.Mask" user "Board Geometry/Soldermask Top")
		(3 "B.Mask" user "Board Geometry/Soldermask Bottom")
		(17 "Dwgs.User" user "User.Drawings")
		(19 "Cmts.User" user "User.Comments")
		(21 "Eco1.User" user "User.Eco1")
		(23 "Eco2.User" user "User.Eco2")
		(25 "Edge.Cuts" user "Board Geometry/Outline")
		(27 "Margin" user)
		(31 "F.CrtYd" user "Package Geometry/Place Bound Top")
		(29 "B.CrtYd" user "Package Geometry/Place Bound Bottom")
		(35 "F.Fab" user "Ref Des/Assembly Top")
		(33 "B.Fab" user "Ref Des/Assembly Bottom")
	)
	(footprint ""
		(layer "F.Cu")
		(at 257.1496 -14.9606 90)
		(property "Reference" "R1049"
			(at 0 0 90)
			(layer "F.SilkS")
			(hide yes)
			(effects
				(font
					(size 1.27 1.27)
				)
			)
		)
		(property "Value" "100KR2F-L1-GP"
			(at 0.064008 -3.993896 90)
			(unlocked yes)
			(layer "F.Fab")
			(hide yes)
			(effects
				(font
					(size 1.016 1.016)
					(thickness 0.1524)
				)
			)
		)
		(property "Device Type" "R402H16"
			(at 0.064008 -5.517896 90)
			(unlocked yes)
			(layer "F.Fab")
			(hide yes)
			(effects
				(font
					(size 1.016 1.016)
					(thickness 0.1524)
				)
			)
		)
		(duplicate_pad_numbers_are_jumpers no)
		(fp_line
			(start 0.508 -0.9398)
			(end -0.508 -0.9398)
			(stroke
				(width 0.1524)
				(type default)
			)
			(layer "F.SilkS")
		)
		(fp_line
			(start -0.508 -0.9398)
			(end -0.508 0.9398)
			(stroke
				(width 0.1524)
				(type default)
			)
			(layer "F.SilkS")
		)
		(fp_rect
			(start -0.508 0.9398)
			(end 0.508 -0.9398)
			(stroke
				(width 0)
				(type default)
			)
			(fill no)
			(layer "F.CrtYd")
		)
		(fp_rect
			(start -0.508 0.9398)
			(end 0.508 -0.9398)
			(stroke
				(width 0)
				(type default)
			)
			(fill no)
			(layer "F.Fab")
		)
		(pad "1" smd custom
			(at 0 -0.4445 90)
			(size 0.1397 0.1397)
			(layers "F.Cu" "F.Mask" "F.Paste")
			(net "PCIE_COMP_A_RST_5")
			(options
				(clearance outline)
				(anchor circle)
			)
			(primitives
				(gr_poly
					(pts
						(arc
							(start -0.1778 -0.2794)
							(mid -0.249642 -0.249642)
							(end -0.2794 -0.1778)
						)
						(arc
							(start -0.2794 0.1778)
							(mid -0.249642 0.249642)
							(end -0.1778 0.2794)
						)
						(arc
							(start 0.1778 0.2794)
							(mid 0.249642 0.249642)
							(end 0.2794 0.1778)
						)
						(arc
							(start 0.2794 -0.1778)
							(mid 0.249642 -0.249642)
							(end 0.1778 -0.2794)
						)
					)
					(width 0)
					(fill yes)
				)
			)
		)
		(pad "2" smd custom
			(at 0 0.4445 90)
			(size 0.1397 0.1397)
			(layers "F.Cu" "F.Mask" "F.Paste")
			(net "GND")
			(options
				(clearance outline)
				(anchor circle)
			)
			(primitives
				(gr_poly
					(pts
						(arc
							(start -0.1778 -0.2794)
							(mid -0.249642 -0.249642)
							(end -0.2794 -0.1778)
						)
						(arc
							(start -0.2794 0.1778)
							(mid -0.249642 0.249642)
							(end -0.1778 0.2794)
						)
						(arc
							(start 0.1778 0.2794)
							(mid 0.249642 0.249642)
							(end 0.2794 0.1778)
						)
						(arc
							(start 0.2794 -0.1778)
							(mid 0.249642 -0.249642)
							(end 0.1778 -0.2794)
						)
					)
					(width 0)
					(fill yes)
				)
			)
		)
	)
	(footprint ""
		(layer "F.Cu")
		(at 440.180984 -293.841932)
		(property "Reference" "Q298"
			(at 0 0 0)
			(layer "F.SilkS")
			(hide yes)
			(effects
				(font
					(size 1.27 1.27)
				)
			)
		)
		(property "Value" "2N7002K-2-GP"
			(at 0.127 -8.9662 0)
			(unlocked yes)
			(layer "F.Fab")
			(hide yes)
			(effects
				(font
					(size 1.016 1.016)
					(thickness 0.1524)
				)
			)
		)
		(property "Device Type" "SOT23DGS2D4H44"
			(at 0.127 -10.4902 0)
			(unlocked yes)
			(layer "F.Fab")
			(hide yes)
			(effects
				(font
					(size 1.016 1.016)
					(thickness 0.1524)
				)
			)
		)
		(duplicate_pad_numbers_are_jumpers no)
		(fp_line
			(start -1.651 -1.778)
			(end -1.651 1.778)
			(stroke
				(width 0.1524)
				(type default)
			)
			(layer "F.SilkS")
		)
		(fp_line
			(start -1.651 1.778)
			(end 1.651 1.778)
			(stroke
				(width 0.1524)
				(type default)
			)
			(layer "F.SilkS")
		)
		(fp_line
			(start 1.651 -1.778)
			(end -1.651 -1.778)
			(stroke
				(width 0.1524)
				(type default)
			)
			(layer "F.SilkS")
		)
		(fp_line
			(start 1.651 1.778)
			(end 1.651 -1.778)
			(stroke
				(width 0.1524)
				(type default)
			)
			(layer "F.SilkS")
		)
		(fp_poly
			(pts
				(xy -1.778 1.8796) (xy -1.778 -1.8796) (xy 1.778 -1.8796) (xy 1.778 1.8796)
			)
			(stroke
				(width 0)
				(type default)
			)
			(fill no)
			(layer "F.CrtYd")
		)
		(fp_poly
			(pts
				(xy -1.778 1.8796) (xy -1.778 -1.8796) (xy 1.778 -1.8796) (xy 1.778 1.8796)
			)
			(stroke
				(width 0)
				(type default)
			)
			(fill no)
			(layer "F.Fab")
		)
		(pad "D" smd custom
			(at 0 -0.9525)
			(size 0.1905 0.1905)
			(layers "F.Cu" "F.Mask" "F.Paste")
			(net "FLT_HDD34_N")
			(options
				(clearance outline)
				(anchor circle)
			)
			(primitives
				(gr_poly
					(pts
						(arc
							(start -0.1778 0.5715)
							(mid -0.321484 0.511984)
							(end -0.381 0.3683)
						)
						(arc
							(start -0.381 -0.3683)
							(mid -0.321484 -0.511984)
							(end -0.1778 -0.5715)
						)
						(arc
							(start 0.1778 -0.5715)
							(mid 0.321484 -0.511984)
							(end 0.381 -0.3683)
						)
						(arc
							(start 0.381 0.3683)
							(mid 0.321484 0.511984)
							(end 0.1778 0.5715)
						)
					)
					(width 0)
					(fill yes)
				)
			)
		)
		(pad "G" smd custom
			(at -0.98425 0.9525)
			(size 0.1905 0.1905)
			(layers "F.Cu" "F.Mask" "F.Paste")
			(net "DRIVE_B_34_FLT_LED")
			(options
				(clearance outline)
				(anchor circle)
			)
			(primitives
				(gr_poly
					(pts
						(arc
							(start -0.1778 0.5715)
							(mid -0.321484 0.511984)
							(end -0.381 0.3683)
						)
						(arc
							(start -0.381 -0.3683)
							(mid -0.321484 -0.511984)
							(end -0.1778 -0.5715)
						)
						(arc
							(start 0.1778 -0.5715)
							(mid 0.321484 -0.511984)
							(end 0.381 -0.3683)
						)
						(arc
							(start 0.381 0.3683)
							(mid 0.321484 0.511984)
							(end 0.1778 0.5715)
						)
					)
					(width 0)
					(fill yes)
				)
			)
		)
		(pad "S" smd custom
			(at 0.98425 0.9525)
			(size 0.1905 0.1905)
			(layers "F.Cu" "F.Mask" "F.Paste")
			(net "GND")
			(options
				(clearance outline)
				(anchor circle)
			)
			(primitives
				(gr_poly
					(pts
						(arc
							(start -0.1778 0.5715)
							(mid -0.321484 0.511984)
							(end -0.381 0.3683)
						)
						(arc
							(start -0.381 -0.3683)
							(mid -0.321484 -0.511984)
							(end -0.1778 -0.5715)
						)
						(arc
							(start 0.1778 -0.5715)
							(mid 0.321484 -0.511984)
							(end 0.381 -0.3683)
						)
						(arc
							(start 0.381 0.3683)
							(mid 0.321484 0.511984)
							(end 0.1778 0.5715)
						)
					)
					(width 0)
					(fill yes)
				)
			)
		)
	)
	(footprint ""
		(layer "F.Cu")
		(at 281.708352 14.138148 90)
		(property "Reference" "C107"
			(at 0 0 90)
			(layer "F.SilkS")
			(hide yes)
			(effects
				(font
					(size 1.27 1.27)
				)
			)
		)
		(property "Value" "SCD1U16V2KX-3GP"
			(at 1.1811 -2.7051 90)
			(unlocked yes)
			(layer "F.Fab")
			(hide yes)
			(effects
				(font
					(size 1.016 1.016)
					(thickness 0.1524)
				)
			)
		)
		(property "Device Type" "C402H22"
			(at 1.1811 -4.2291 90)
			(unlocked yes)
			(layer "F.Fab")
			(hide yes)
			(effects
				(font
					(size 1.016 1.016)
					(thickness 0.1524)
				)
			)
		)
		(duplicate_pad_numbers_are_jumpers no)
		(fp_rect
			(start -0.4318 0.9525)
			(end 0.4318 -0.9525)
			(stroke
				(width 0)
				(type default)
			)
			(fill no)
			(layer "F.CrtYd")
		)
		(fp_rect
			(start -0.4318 0.9525)
			(end 0.4318 -0.9525)
			(stroke
				(width 0)
				(type default)
			)
			(fill no)
			(layer "F.Fab")
		)
		(pad "1" smd custom
			(at 0 -0.4445 90)
			(size 0.1524 0.1524)
			(layers "F.Cu" "F.Mask" "F.Paste")
			(net "P3V3_BIAS")
			(options
				(clearance outline)
				(anchor circle)
			)
			(primitives
				(gr_poly
					(pts
						(arc
							(start 0.3048 -0.2032)
							(mid 0.275042 -0.275042)
							(end 0.2032 -0.3048)
						)
						(arc
							(start -0.2032 -0.3048)
							(mid -0.275042 -0.275042)
							(end -0.3048 -0.2032)
						)
						(arc
							(start -0.3048 0.2032)
							(mid -0.275042 0.275042)
							(end -0.2032 0.3048)
						)
						(arc
							(start 0.2032 0.3048)
							(mid 0.275042 0.275042)
							(end 0.3048 0.2032)
						)
					)
					(width 0)
					(fill yes)
				)
			)
		)
		(pad "2" smd custom
			(at 0 0.4445 90)
			(size 0.1524 0.1524)
			(layers "F.Cu" "F.Mask" "F.Paste")
			(net "GND")
			(options
				(clearance outline)
				(anchor circle)
			)
			(primitives
				(gr_poly
					(pts
						(arc
							(start 0.3048 -0.2032)
							(mid 0.275042 -0.275042)
							(end 0.2032 -0.3048)
						)
						(arc
							(start -0.2032 -0.3048)
							(mid -0.275042 -0.275042)
							(end -0.3048 -0.2032)
						)
						(arc
							(start -0.3048 0.2032)
							(mid -0.275042 0.275042)
							(end -0.2032 0.3048)
						)
						(arc
							(start 0.2032 0.3048)
							(mid 0.275042 0.275042)
							(end 0.3048 0.2032)
						)
					)
					(width 0)
					(fill yes)
				)
			)
		)
	)
	(footprint ""
		(layer "F.Cu")
		(at 50.152046 -275.633942)
		(property "Reference" "R170"
			(at 0 0 0)
			(layer "F.SilkS")
			(hide yes)
			(effects
				(font
					(size 1.27 1.27)
				)
			)
		)
		(property "Value" "0R2J-2-GP"
			(at 0.064008 -3.993896 0)
			(unlocked yes)
			(layer "F.Fab")
			(hide yes)
			(effects
				(font
					(size 1.016 1.016)
					(thickness 0.1524)
				)
			)
		)
		(property "Device Type" "R402H16"
			(at 0.064008 -5.517896 0)
			(unlocked yes)
			(layer "F.Fab")
			(hide yes)
			(effects
				(font
					(size 1.016 1.016)
					(thickness 0.1524)
				)
			)
		)
		(duplicate_pad_numbers_are_jumpers no)
		(fp_line
			(start -0.508 -0.9398)
			(end -0.508 0.9398)
			(stroke
				(width 0.1524)
				(type default)
			)
			(layer "F.SilkS")
		)
		(fp_line
			(start 0.508 -0.9398)
			(end -0.508 -0.9398)
			(stroke
				(width 0.1524)
				(type default)
			)
			(layer "F.SilkS")
		)
		(fp_rect
			(start -0.508 0.9398)
			(end 0.508 -0.9398)
			(stroke
				(width 0)
				(type default)
			)
			(fill no)
			(layer "F.CrtYd")
		)
		(fp_rect
			(start -0.508 0.9398)
			(end 0.508 -0.9398)
			(stroke
				(width 0)
				(type default)
			)
			(fill no)
			(layer "F.Fab")
		)
		(pad "1" smd custom
			(at 0 -0.4445)
			(size 0.1397 0.1397)
			(layers "F.Cu" "F.Mask" "F.Paste")
			(net "SW_HDD_G1")
			(options
				(clearance outline)
				(anchor circle)
			)
			(primitives
				(gr_poly
					(pts
						(arc
							(start -0.1778 -0.2794)
							(mid -0.249642 -0.249642)
							(end -0.2794 -0.1778)
						)
						(arc
							(start -0.2794 0.1778)
							(mid -0.249642 0.249642)
							(end -0.1778 0.2794)
						)
						(arc
							(start 0.1778 0.2794)
							(mid 0.249642 0.249642)
							(end 0.2794 0.1778)
						)
						(arc
							(start 0.2794 -0.1778)
							(mid 0.249642 -0.249642)
							(end 0.1778 -0.2794)
						)
					)
					(width 0)
					(fill yes)
				)
			)
		)
		(pad "2" smd custom
			(at 0 0.4445)
			(size 0.1397 0.1397)
			(layers "F.Cu" "F.Mask" "F.Paste")
			(net "SW_HDD_R1")
			(options
				(clearance outline)
				(anchor circle)
			)
			(primitives
				(gr_poly
					(pts
						(arc
							(start -0.1778 -0.2794)
							(mid -0.249642 -0.249642)
							(end -0.2794 -0.1778)
						)
						(arc
							(start -0.2794 0.1778)
							(mid -0.249642 0.249642)
							(end -0.1778 0.2794)
						)
						(arc
							(start 0.1778 0.2794)
							(mid 0.249642 0.249642)
							(end 0.2794 0.1778)
						)
						(arc
							(start 0.2794 -0.1778)
							(mid 0.249642 -0.249642)
							(end 0.1778 -0.2794)
						)
					)
					(width 0)
					(fill yes)
				)
			)
		)
	)
)
